(kicad_pcb
	(version 20260206)
	(generator "pcbnew")
	(generator_version "10.0")
	(general
		(thickness 1.6)
		(legacy_teardrops no)
	)
	(paper "A4")
	(title_block
		(title "timecard-production-celestica-r4006 — R4006-B0001-02_R01.brd")
		(comment 1 "Time Appliance Project (Time Card) / footprints 112-115 of 1113")
	)
	(layers
		(0 "F.Cu" signal "TOP")
		(4 "In1.Cu" signal "L02_GND1")
		(6 "In2.Cu" signal "L03_SIG1")
		(8 "In3.Cu" signal "L04_GND2")
		(10 "In4.Cu" signal "L05_VCC1")
		(12 "In5.Cu" signal "L06_VCC2")
		(14 "In6.Cu" signal "L07_GND3")
		(16 "In7.Cu" signal "L08_SIG2")
		(18 "In8.Cu" signal "L09_GND4")
		(2 "B.Cu" signal "BOTTOM")
		(9 "F.Adhes" user "F.Adhesive")
		(11 "B.Adhes" user "B.Adhesive")
		(13 "F.Paste" user "Package Geometry/Pastemask Top")
		(15 "B.Paste" user "Package Geometry/Pastemask Bottom")
		(5 "F.SilkS" user "Ref Des/Silkscreen Top")
		(7 "B.SilkS" user "Ref Des/Silkscreen Bottom")
		(1 "F.Mask" user "Board Geometry/Soldermask Top")
		(3 "B.Mask" user "Board Geometry/Soldermask Bottom")
		(17 "Dwgs.User" user "User.Drawings")
		(19 "Cmts.User" user "User.Comments")
		(21 "Eco1.User" user "User.Eco1")
		(23 "Eco2.User" user "User.Eco2")
		(25 "Edge.Cuts" user "Board Geometry/Outline")
		(27 "Margin" user)
		(31 "F.CrtYd" user "Package Geometry/Place Bound Top")
		(29 "B.CrtYd" user "Package Geometry/Place Bound Bottom")
		(35 "F.Fab" user "Ref Des/Assembly Top")
		(33 "B.Fab" user "Ref Des/Assembly Bottom")
	)
	(footprint ""
		(layer "F.Cu")
		(at 125.499876 -104.650032)
		(property "Reference" "ME3"
			(at -5.929376 -0.085598 0)
			(unlocked yes)
			(layer "F.SilkS")
			(effects
				(font
					(size 0.7874 0.5842)
					(thickness 0.1524)
				)
				(justify left)
			)
		)
		(property "Value" ""
			(at 0 0 0)
			(layer "F.Fab")
			(effects
				(font
					(size 1.27 1.27)
				)
			)
		)
		(property "Device Type" "NUT-G340-10437-01"
			(at -1.4732 4.226306 0)
			(unlocked yes)
			(layer "F.Fab")
			(hide yes)
			(effects
				(font
					(size 0.7874 0.5842)
					(thickness 0.1524)
				)
				(justify left)
			)
		)
		(property "User Part Number" "PARTNUM*"
			(at -3.048 5.242306 0)
			(unlocked yes)
			(layer "Cmts.User")
			(hide yes)
			(effects
				(font
					(size 0.7874 0.5842)
					(thickness 0.1524)
				)
				(justify left)
			)
		)
		(duplicate_pad_numbers_are_jumpers no)
		(fp_circle
			(center 0 0)
			(end 3.3528 0)
			(stroke
				(width 0.1)
				(type default)
			)
			(fill no)
			(layer "F.SilkS")
		)
		(fp_poly
			(pts
				(arc
					(start -2.102612 -0.1524)
					(mid -1.490671 -1.490671)
					(end -0.1524 -2.102612)
				)
				(arc
					(start -0.1524 -3.171444)
					(mid -2.245137 -2.245137)
					(end -3.171444 -0.1524)
				)
			)
			(stroke
				(width 0)
				(type default)
			)
			(fill yes)
			(layer "F.Paste")
		)
		(fp_poly
			(pts
				(arc
					(start -0.1524 2.102612)
					(mid -1.490671 1.490671)
					(end -2.102612 0.1524)
				)
				(arc
					(start -3.171444 0.1524)
					(mid -2.245137 2.245137)
					(end -0.1524 3.171444)
				)
			)
			(stroke
				(width 0)
				(type default)
			)
			(fill yes)
			(layer "F.Paste")
		)
		(fp_poly
			(pts
				(arc
					(start 0.1524 -2.102612)
					(mid 1.490671 -1.490671)
					(end 2.102612 -0.1524)
				)
				(arc
					(start 3.171444 -0.1524)
					(mid 2.245137 -2.245137)
					(end 0.1524 -3.171444)
				)
			)
			(stroke
				(width 0)
				(type default)
			)
			(fill yes)
			(layer "F.Paste")
		)
		(fp_poly
			(pts
				(arc
					(start 2.102612 0.1524)
					(mid 1.490671 1.490671)
					(end 0.1524 2.102612)
				)
				(arc
					(start 0.1524 3.171444)
					(mid 2.245137 2.245137)
					(end 3.171444 0.1524)
				)
			)
			(stroke
				(width 0)
				(type default)
			)
			(fill yes)
			(layer "F.Paste")
		)
		(fp_rect
			(start -7.5946 7.5946)
			(end 7.5946 -7.5946)
			(stroke
				(width 0)
				(type default)
			)
			(fill no)
			(layer "B.CrtYd")
		)
		(fp_poly
			(pts
				(arc
					(start 3.6068 0)
					(mid -3.6068 0)
					(end 3.6068 0)
				)
			)
			(stroke
				(width 0)
				(type default)
			)
			(fill no)
			(layer "F.CrtYd")
		)
		(fp_circle
			(center 0 0)
			(end 2.8448 0)
			(stroke
				(width 0.1)
				(type default)
			)
			(fill no)
			(layer "F.Fab")
		)
		(pad "1" thru_hole circle
			(at 0 0)
			(size 6.1976 6.1976)
			(drill 4.2164)
			(layers "*.Cu" "*.Mask")
			(remove_unused_layers no)
			(net "SG")
			(padstack
				(mode front_inner_back)
				(layer "Inner"
					(shape circle)
					(size 5.0292 5.0292)
					(clearance -0.1143)
				)
				(layer "B.Cu"
					(shape circle)
					(size 5.0292 5.0292)
				)
			)
		)
	)
	(footprint ""
		(layer "F.Cu")
		(at 12.192 -37.211 90)
		(property "Reference" "R367"
			(at -1.27 -3.26263 90)
			(unlocked yes)
			(layer "F.SilkS")
			(effects
				(font
					(size 0.7874 0.5842)
					(thickness 0.1524)
				)
			)
		)
		(property "Value" "VAL*"
			(at 0.02032 2.13233 90)
			(unlocked yes)
			(layer "F.Fab")
			(hide yes)
			(effects
				(font
					(size 0.7874 0.5842)
					(thickness 0.1524)
				)
			)
		)
		(property "Tolerance" "TOL*"
			(at 0.044704 3.05435 90)
			(unlocked yes)
			(layer "Cmts.User")
			(hide yes)
			(effects
				(font
					(size 0.7874 0.5842)
					(thickness 0.1524)
				)
			)
		)
		(property "User Part Number" "PARTNUM*"
			(at 0.02032 4.024884 90)
			(unlocked yes)
			(layer "Cmts.User")
			(hide yes)
			(effects
				(font
					(size 0.7874 0.5842)
					(thickness 0.1524)
				)
			)
		)
		(property "Device Type" "RESISTOR-G155-149R9-01,49.9OHMA"
			(at 0.008382 1.210564 90)
			(unlocked yes)
			(layer "F.Fab")
			(hide yes)
			(effects
				(font
					(size 0.7874 0.5842)
					(thickness 0.1524)
				)
			)
		)
		(duplicate_pad_numbers_are_jumpers no)
		(fp_line
			(start 1.143 -0.5588)
			(end -1.143 -0.5588)
			(stroke
				(width 0.1)
				(type default)
			)
			(layer "F.SilkS")
		)
		(fp_line
			(start -1.143 -0.5588)
			(end -1.143 0.5588)
			(stroke
				(width 0.1)
				(type default)
			)
			(layer "F.SilkS")
		)
		(fp_line
			(start 1.143 0.5588)
			(end 1.143 -0.5588)
			(stroke
				(width 0.1)
				(type default)
			)
			(layer "F.SilkS")
		)
		(fp_line
			(start -1.143 0.5588)
			(end 1.143 0.5588)
			(stroke
				(width 0.1)
				(type default)
			)
			(layer "F.SilkS")
		)
		(fp_poly
			(pts
				(xy -1.143 0.5588) (xy 1.143 0.5588) (xy 1.143 -0.5588) (xy -1.143 -0.5588)
			)
			(stroke
				(width 0)
				(type default)
			)
			(fill no)
			(layer "F.CrtYd")
		)
		(fp_line
			(start 0.508 -0.3048)
			(end -0.508 -0.3048)
			(stroke
				(width 0.1)
				(type default)
			)
			(layer "F.Fab")
		)
		(fp_line
			(start -0.508 -0.3048)
			(end -0.508 0.3048)
			(stroke
				(width 0.1)
				(type default)
			)
			(layer "F.Fab")
		)
		(fp_line
			(start 0.508 0.3048)
			(end 0.508 -0.3048)
			(stroke
				(width 0.1)
				(type default)
			)
			(layer "F.Fab")
		)
		(fp_line
			(start -0.508 0.3048)
			(end 0.508 0.3048)
			(stroke
				(width 0.1)
				(type default)
			)
			(layer "F.Fab")
		)
		(pad "1" smd rect
			(at -0.5334 0 90)
			(size 0.7112 0.6096)
			(layers "F.Cu" "F.Mask" "F.Paste")
			(net "BF_ANT3_IN")
		)
		(pad "2" smd rect
			(at 0.5334 0 90)
			(size 0.7112 0.6096)
			(layers "F.Cu" "F.Mask" "F.Paste")
			(net "ANT3_IN")
		)
		(zone
			(layer "F.Cu")
			(hatch none 0.5)
			(connect_pads
				(clearance 0)
			)
			(min_thickness 0.25)
			(keepout
				(tracks allowed)
				(vias not_allowed)
				(pads allowed)
				(copperpour not_allowed)
				(footprints allowed)
			)
			(placement
				(enabled no)
				(sheetname "")
			)
			(fill
				(thermal_gap 0.5)
				(thermal_bridge_width 0.5)
				(island_removal_mode 0)
			)
			(polygon
				(pts
					(xy 12.4968 -37.1348) (xy 12.4968 -37.2872) (xy 11.8872 -37.2872) (xy 11.8872 -37.1348)
				)
			)
		)
		(zone
			(layer "F.Cu")
			(hatch none 0.5)
			(connect_pads
				(clearance 0)
			)
			(min_thickness 0.25)
			(keepout
				(tracks not_allowed)
				(vias allowed)
				(pads allowed)
				(copperpour not_allowed)
				(footprints allowed)
			)
			(placement
				(enabled no)
				(sheetname "")
			)
			(fill
				(thermal_gap 0.5)
				(thermal_bridge_width 0.5)
				(island_removal_mode 0)
			)
			(polygon
				(pts
					(xy 12.4968 -37.1348) (xy 12.4968 -37.2872) (xy 11.8872 -37.2872) (xy 11.8872 -37.1348)
				)
			)
		)
	)
	(footprint ""
		(layer "F.Cu")
		(at 84.328 -93.599 90)
		(property "Reference" "C21"
			(at -3.81 -3.89763 90)
			(unlocked yes)
			(layer "F.SilkS")
			(effects
				(font
					(size 0.7874 0.5842)
					(thickness 0.1524)
				)
			)
		)
		(property "Value" "VAL*"
			(at 0.0762 3.134106 90)
			(unlocked yes)
			(layer "F.Fab")
			(hide yes)
			(effects
				(font
					(size 0.7874 0.5842)
					(thickness 0.1524)
				)
			)
		)
		(property "Tolerance" "TOL*"
			(at 0.0762 4.048506 90)
			(unlocked yes)
			(layer "Cmts.User")
			(hide yes)
			(effects
				(font
					(size 0.7874 0.5842)
					(thickness 0.1524)
				)
			)
		)
		(property "User Part Number" "PARTNUM*"
			(at 0.1016 5.013706 90)
			(unlocked yes)
			(layer "Cmts.User")
			(hide yes)
			(effects
				(font
					(size 0.7874 0.5842)
					(thickness 0.1524)
				)
			)
		)
		(property "Device Type" "CAPACITOR-G107-0F226-CM,22UF,2A"
			(at 0.0508 2.194306 90)
			(unlocked yes)
			(layer "F.Fab")
			(hide yes)
			(effects
				(font
					(size 0.7874 0.5842)
					(thickness 0.1524)
				)
			)
		)
		(duplicate_pad_numbers_are_jumpers no)
		(fp_line
			(start 1.5748 -0.9398)
			(end -1.5748 -0.9398)
			(stroke
				(width 0.1)
				(type default)
			)
			(layer "F.SilkS")
		)
		(fp_line
			(start -1.5748 -0.9398)
			(end -1.5748 0.9398)
			(stroke
				(width 0.1)
				(type default)
			)
			(layer "F.SilkS")
		)
		(fp_line
			(start 1.5748 0.9398)
			(end 1.5748 -0.9398)
			(stroke
				(width 0.1)
				(type default)
			)
			(layer "F.SilkS")
		)
		(fp_line
			(start -1.5748 0.9398)
			(end 1.5748 0.9398)
			(stroke
				(width 0.1)
				(type default)
			)
			(layer "F.SilkS")
		)
		(fp_rect
			(start -1.5748 -0.9398)
			(end 1.5748 0.9398)
			(stroke
				(width 0)
				(type default)
			)
			(fill no)
			(layer "F.CrtYd")
		)
		(fp_line
			(start 1.016 -0.635)
			(end -1.016 -0.635)
			(stroke
				(width 0.1)
				(type default)
			)
			(layer "F.Fab")
		)
		(fp_line
			(start -1.016 -0.635)
			(end -1.016 0.635)
			(stroke
				(width 0.1)
				(type default)
			)
			(layer "F.Fab")
		)
		(fp_line
			(start 1.016 0.635)
			(end 1.016 -0.635)
			(stroke
				(width 0.1)
				(type default)
			)
			(layer "F.Fab")
		)
		(fp_line
			(start -1.016 0.635)
			(end 1.016 0.635)
			(stroke
				(width 0.1)
				(type default)
			)
			(layer "F.Fab")
		)
		(pad "1" smd rect
			(at -0.8382 0 90)
			(size 0.9652 1.3716)
			(layers "F.Cu" "F.Mask" "F.Paste")
			(net "XP3R3V")
		)
		(pad "2" smd rect
			(at 0.8382 0 90)
			(size 0.9652 1.3716)
			(layers "F.Cu" "F.Mask" "F.Paste")
			(net "SG")
		)
		(zone
			(layer "F.Cu")
			(hatch none 0.5)
			(connect_pads
				(clearance 0)
			)
			(min_thickness 0.25)
			(keepout
				(tracks allowed)
				(vias not_allowed)
				(pads allowed)
				(copperpour not_allowed)
				(footprints allowed)
			)
			(placement
				(enabled no)
				(sheetname "")
			)
			(fill
				(thermal_gap 0.5)
				(thermal_bridge_width 0.5)
				(island_removal_mode 0)
			)
			(polygon
				(pts
					(xy 83.693 -93.3704) (xy 84.963 -93.3704) (xy 84.963 -93.8276) (xy 83.693 -93.8276)
				)
			)
		)
	)
	(footprint ""
		(layer "F.Cu")
		(at 82.7786 -50.546 -90)
		(property "Reference" "R276"
			(at 14.478 1.09093 90)
			(unlocked yes)
			(layer "F.SilkS")
			(effects
				(font
					(size 0.7874 0.5842)
					(thickness 0.1524)
				)
			)
		)
		(property "Value" "VAL*"
			(at 0.02032 2.13233 270)
			(unlocked yes)
			(layer "F.Fab")
			(hide yes)
			(effects
				(font
					(size 0.7874 0.5842)
					(thickness 0.1524)
				)
			)
		)
		(property "Tolerance" "TOL*"
			(at 0.044704 3.05435 270)
			(unlocked yes)
			(layer "Cmts.User")
			(hide yes)
			(effects
				(font
					(size 0.7874 0.5842)
					(thickness 0.1524)
				)
			)
		)
		(property "User Part Number" "PARTNUM*"
			(at 0.02032 4.024884 270)
			(unlocked yes)
			(layer "Cmts.User")
			(hide yes)
			(effects
				(font
					(size 0.7874 0.5842)
					(thickness 0.1524)
				)
			)
		)
		(property "Device Type" "RESISTOR-G155-11000-01,100OHM,A"
			(at 0.008382 1.210564 270)
			(unlocked yes)
			(layer "F.Fab")
			(hide yes)
			(effects
				(font
					(size 0.7874 0.5842)
					(thickness 0.1524)
				)
			)
		)
		(duplicate_pad_numbers_are_jumpers no)
		(fp_line
			(start -1.143 0.5588)
			(end 1.143 0.5588)
			(stroke
				(width 0.1)
				(type default)
			)
			(layer "F.SilkS")
		)
		(fp_line
			(start 1.143 0.5588)
			(end 1.143 -0.5588)
			(stroke
				(width 0.1)
				(type default)
			)
			(layer "F.SilkS")
		)
		(fp_line
			(start -1.143 -0.5588)
			(end -1.143 0.5588)
			(stroke
				(width 0.1)
				(type default)
			)
			(layer "F.SilkS")
		)
		(fp_line
			(start 1.143 -0.5588)
			(end -1.143 -0.5588)
			(stroke
				(width 0.1)
				(type default)
			)
			(layer "F.SilkS")
		)
		(fp_rect
			(start 1.143 0.5588)
			(end -1.143 -0.5588)
			(stroke
				(width 0)
				(type default)
			)
			(fill no)
			(layer "F.CrtYd")
		)
		(fp_line
			(start -0.508 0.3048)
			(end 0.508 0.3048)
			(stroke
				(width 0.1)
				(type default)
			)
			(layer "F.Fab")
		)
		(fp_line
			(start 0.508 0.3048)
			(end 0.508 -0.3048)
			(stroke
				(width 0.1)
				(type default)
			)
			(layer "F.Fab")
		)
		(fp_line
			(start -0.508 -0.3048)
			(end -0.508 0.3048)
			(stroke
				(width 0.1)
				(type default)
			)
			(layer "F.Fab")
		)
		(fp_line
			(start 0.508 -0.3048)
			(end -0.508 -0.3048)
			(stroke
				(width 0.1)
				(type default)
			)
			(layer "F.Fab")
		)
		(pad "1" smd rect
			(at -0.5334 0 270)
			(size 0.7112 0.6096)
			(layers "F.Cu" "F.Mask" "F.Paste")
			(net "FPGA_OUT_MAC_PPS_IN0P")
		)
		(pad "2" smd rect
			(at 0.5334 0 270)
			(size 0.7112 0.6096)
			(layers "F.Cu" "F.Mask" "F.Paste")
			(net "FPGA_OUT_MAC_PPS_IN0N")
		)
		(zone
			(layer "F.Cu")
			(hatch none 0.5)
			(connect_pads
				(clearance 0)
			)
			(min_thickness 0.25)
			(keepout
				(tracks allowed)
				(vias not_allowed)
				(pads allowed)
				(copperpour not_allowed)
				(footprints allowed)
			)
			(placement
				(enabled no)
				(sheetname "")
			)
			(fill
				(thermal_gap 0.5)
				(thermal_bridge_width 0.5)
				(island_removal_mode 0)
			)
			(polygon
				(pts
					(xy 82.4738 -50.4698) (xy 83.0834 -50.4698) (xy 83.0834 -50.6222) (xy 82.4738 -50.6222)
				)
			)
		)
	)
)
